(kicad_pcb
	(version 20260206)
	(generator "pcbnew")
	(generator_version "10.0")
	(general
		(thickness 1.6)
		(legacy_teardrops no)
	)
	(paper "A4")
	(title_block
		(title "03242023_DA0F0TMBIJ0_F0T_Motherboard_J_brd_V01_OCP.brd")
		(comment 1 "Grand Teton / footprints 3331-3337 of 6105")
	)
	(layers
		(0 "F.Cu" signal "TOP")
		(4 "In1.Cu" signal "GND")
		(6 "In2.Cu" signal "IN1")
		(8 "In3.Cu" signal "GND1")
		(10 "In4.Cu" signal "IN2")
		(12 "In5.Cu" signal "GND2")
		(14 "In6.Cu" signal "IN3")
		(16 "In7.Cu" signal "GND3")
		(18 "In8.Cu" signal "VCC")
		(20 "In9.Cu" signal "VCC1")
		(22 "In10.Cu" signal "GND4")
		(24 "In11.Cu" signal "IN4")
		(26 "In12.Cu" signal "GND5")
		(28 "In13.Cu" signal "IN5")
		(30 "In14.Cu" signal "GND6")
		(32 "In15.Cu" signal "IN6")
		(34 "In16.Cu" signal "GND7")
		(2 "B.Cu" signal "BOTTOM")
		(9 "F.Adhes" user "F.Adhesive")
		(11 "B.Adhes" user "B.Adhesive")
		(13 "F.Paste" user "Package Geometry/Pastemask Top")
		(15 "B.Paste" user "Package Geometry/Pastemask Bottom")
		(5 "F.SilkS" user "Ref Des/Silkscreen Top")
		(7 "B.SilkS" user "Ref Des/Silkscreen Bottom")
		(1 "F.Mask" user "Board Geometry/Soldermask Top")
		(3 "B.Mask" user "Board Geometry/Soldermask Bottom")
		(17 "Dwgs.User" user "User.Drawings")
		(19 "Cmts.User" user "User.Comments")
		(21 "Eco1.User" user "User.Eco1")
		(23 "Eco2.User" user "User.Eco2")
		(25 "Edge.Cuts" user "Board Geometry/Outline")
		(27 "Margin" user)
		(31 "F.CrtYd" user "Package Geometry/Place Bound Top")
		(29 "B.CrtYd" user "Package Geometry/Place Bound Bottom")
		(35 "F.Fab" user "Ref Des/Assembly Top")
		(33 "B.Fab" user "Ref Des/Assembly Bottom")
	)
	(footprint ""
		(layer "F.Cu")
		(at 193.38036 -120.614948 180)
		(property "Reference" "R1313"
			(at 0 0 180)
			(layer "F.SilkS")
			(hide yes)
			(effects
				(font
					(size 1.27 1.27)
				)
			)
		)
		(property "Value" ""
			(at 0 0 180)
			(layer "F.Fab")
			(effects
				(font
					(size 1.27 1.27)
				)
			)
		)
		(duplicate_pad_numbers_are_jumpers no)
		(fp_line
			(start 0.7874 0.4064)
			(end -0.7874 0.4064)
			(stroke
				(width 0.1524)
				(type default)
			)
			(layer "F.SilkS")
		)
		(fp_line
			(start 0.7874 -0.4064)
			(end 0.7874 0.4064)
			(stroke
				(width 0.1524)
				(type default)
			)
			(layer "F.SilkS")
		)
		(fp_line
			(start -0.7874 0.4064)
			(end -0.7874 -0.4064)
			(stroke
				(width 0.1524)
				(type default)
			)
			(layer "F.SilkS")
		)
		(fp_line
			(start -0.7874 -0.4064)
			(end 0.7874 -0.4064)
			(stroke
				(width 0.1524)
				(type default)
			)
			(layer "F.SilkS")
		)
		(fp_line
			(start 0.67945 0.3048)
			(end 0.120396 0.3048)
			(stroke
				(width 0.1)
				(type default)
			)
			(layer "F.Fab")
		)
		(fp_line
			(start 0.67945 -0.3048)
			(end 0.67945 0.3048)
			(stroke
				(width 0.1)
				(type default)
			)
			(layer "F.Fab")
		)
		(fp_line
			(start 0.12065 -0.2794)
			(end 0.12065 -0.3048)
			(stroke
				(width 0.1)
				(type default)
			)
			(layer "F.Fab")
		)
		(fp_line
			(start 0.12065 -0.3048)
			(end 0.67945 -0.3048)
			(stroke
				(width 0.1)
				(type default)
			)
			(layer "F.Fab")
		)
		(fp_line
			(start 0.120396 0.3048)
			(end 0.120396 0.2794)
			(stroke
				(width 0.1)
				(type default)
			)
			(layer "F.Fab")
		)
		(fp_line
			(start 0.120396 0.2794)
			(end -0.12065 0.2794)
			(stroke
				(width 0.1)
				(type default)
			)
			(layer "F.Fab")
		)
		(fp_line
			(start -0.12065 0.3048)
			(end -0.67945 0.3048)
			(stroke
				(width 0.1)
				(type default)
			)
			(layer "F.Fab")
		)
		(fp_line
			(start -0.12065 0.2794)
			(end -0.12065 0.3048)
			(stroke
				(width 0.1)
				(type default)
			)
			(layer "F.Fab")
		)
		(fp_line
			(start -0.12065 -0.2794)
			(end 0.12065 -0.2794)
			(stroke
				(width 0.1)
				(type default)
			)
			(layer "F.Fab")
		)
		(fp_line
			(start -0.12065 -0.305054)
			(end -0.12065 -0.2794)
			(stroke
				(width 0.1)
				(type default)
			)
			(layer "F.Fab")
		)
		(fp_line
			(start -0.67945 0.3048)
			(end -0.67945 -0.305054)
			(stroke
				(width 0.1)
				(type default)
			)
			(layer "F.Fab")
		)
		(fp_line
			(start -0.67945 -0.305054)
			(end -0.12065 -0.305054)
			(stroke
				(width 0.1)
				(type default)
			)
			(layer "F.Fab")
		)
		(pad "1" smd circle
			(at -0.40005 0 180)
			(size 0 0)
			(layers "F.Cu" "F.Mask" "F.Paste")
			(net "FM_PCH_GLB_RST_WARN_N")
		)
		(pad "2" smd circle
			(at 0.40005 0 180)
			(size 0 0)
			(layers "F.Cu" "F.Mask" "F.Paste")
			(net "FM_PCH_PLD_GLB_RST_WARN_N")
		)
	)
	(footprint ""
		(layer "F.Cu")
		(at 370.618258 -417.17341 90)
		(property "Reference" "R4198"
			(at 0 0 90)
			(layer "F.SilkS")
			(hide yes)
			(effects
				(font
					(size 1.27 1.27)
				)
			)
		)
		(property "Value" ""
			(at 0 0 90)
			(layer "F.Fab")
			(effects
				(font
					(size 1.27 1.27)
				)
			)
		)
		(duplicate_pad_numbers_are_jumpers no)
		(fp_line
			(start 0.7874 -0.4064)
			(end 0.7874 0.4064)
			(stroke
				(width 0.1524)
				(type default)
			)
			(layer "F.SilkS")
		)
		(fp_line
			(start -0.7874 -0.4064)
			(end 0.7874 -0.4064)
			(stroke
				(width 0.1524)
				(type default)
			)
			(layer "F.SilkS")
		)
		(fp_line
			(start 0.7874 0.4064)
			(end -0.7874 0.4064)
			(stroke
				(width 0.1524)
				(type default)
			)
			(layer "F.SilkS")
		)
		(fp_line
			(start -0.7874 0.4064)
			(end -0.7874 -0.4064)
			(stroke
				(width 0.1524)
				(type default)
			)
			(layer "F.SilkS")
		)
		(fp_line
			(start -0.12065 -0.305054)
			(end -0.12065 -0.2794)
			(stroke
				(width 0.1)
				(type default)
			)
			(layer "F.Fab")
		)
		(fp_line
			(start -0.67945 -0.305054)
			(end -0.12065 -0.305054)
			(stroke
				(width 0.1)
				(type default)
			)
			(layer "F.Fab")
		)
		(fp_line
			(start 0.67945 -0.3048)
			(end 0.67945 0.3048)
			(stroke
				(width 0.1)
				(type default)
			)
			(layer "F.Fab")
		)
		(fp_line
			(start 0.12065 -0.3048)
			(end 0.67945 -0.3048)
			(stroke
				(width 0.1)
				(type default)
			)
			(layer "F.Fab")
		)
		(fp_line
			(start 0.12065 -0.2794)
			(end 0.12065 -0.3048)
			(stroke
				(width 0.1)
				(type default)
			)
			(layer "F.Fab")
		)
		(fp_line
			(start -0.12065 -0.2794)
			(end 0.12065 -0.2794)
			(stroke
				(width 0.1)
				(type default)
			)
			(layer "F.Fab")
		)
		(fp_line
			(start 0.120396 0.2794)
			(end -0.12065 0.2794)
			(stroke
				(width 0.1)
				(type default)
			)
			(layer "F.Fab")
		)
		(fp_line
			(start -0.12065 0.2794)
			(end -0.12065 0.3048)
			(stroke
				(width 0.1)
				(type default)
			)
			(layer "F.Fab")
		)
		(fp_line
			(start 0.67945 0.3048)
			(end 0.120396 0.3048)
			(stroke
				(width 0.1)
				(type default)
			)
			(layer "F.Fab")
		)
		(fp_line
			(start 0.120396 0.3048)
			(end 0.120396 0.2794)
			(stroke
				(width 0.1)
				(type default)
			)
			(layer "F.Fab")
		)
		(fp_line
			(start -0.12065 0.3048)
			(end -0.67945 0.3048)
			(stroke
				(width 0.1)
				(type default)
			)
			(layer "F.Fab")
		)
		(fp_line
			(start -0.67945 0.3048)
			(end -0.67945 -0.305054)
			(stroke
				(width 0.1)
				(type default)
			)
			(layer "F.Fab")
		)
		(pad "1" smd circle
			(at -0.40005 0 90)
			(size 0 0)
			(layers "F.Cu" "F.Mask" "F.Paste")
			(net "P3V3_AUX")
		)
		(pad "2" smd circle
			(at 0.40005 0 90)
			(size 0 0)
			(layers "F.Cu" "F.Mask" "F.Paste")
			(net "U270_0_ADD1")
		)
	)
	(footprint ""
		(layer "F.Cu")
		(at 102.818946 -352.02114 180)
		(property "Reference" "PJ52"
			(at 1.986788 -1.20904 0)
			(unlocked yes)
			(layer "F.SilkS")
			(effects
				(font
					(size 0.7874 0.5842)
					(thickness 0.1524)
				)
				(justify left)
			)
		)
		(property "Value" ""
			(at 0 0 180)
			(layer "F.Fab")
			(effects
				(font
					(size 1.27 1.27)
				)
			)
		)
		(duplicate_pad_numbers_are_jumpers no)
		(pad "1" smd circle
			(at -0.7493 0 270)
			(size 0 0)
			(layers "F.Cu" "F.Mask" "F.Paste")
			(net "VSENSE_PVCCIN_CPU1_DP")
		)
		(pad "2" smd rect
			(at 0.7493 0 90)
			(size 0.7112 0.8128)
			(layers "F.Cu" "F.Mask" "F.Paste")
			(net "SH_PVCCIN_CPU1")
		)
		(zone
			(layer "F.Cu")
			(hatch none 0.5)
			(connect_pads
				(clearance 0)
			)
			(min_thickness 0.25)
			(keepout
				(tracks allowed)
				(vias not_allowed)
				(pads allowed)
				(copperpour not_allowed)
				(footprints allowed)
			)
			(placement
				(enabled no)
				(sheetname "")
			)
			(fill
				(thermal_gap 0.5)
				(thermal_bridge_width 0.5)
				(island_removal_mode 0)
			)
			(polygon
				(pts
					(xy 101.612446 -351.61474) (xy 104.000046 -351.61474) (xy 104.000046 -352.432366) (xy 101.612446 -352.432366)
				)
			)
		)
	)
	(footprint ""
		(layer "F.Cu")
		(at 215.90381 -23.304754 -90)
		(property "Reference" "R1139"
			(at 0 0 270)
			(layer "F.SilkS")
			(hide yes)
			(effects
				(font
					(size 1.27 1.27)
				)
			)
		)
		(property "Value" ""
			(at 0 0 270)
			(layer "F.Fab")
			(effects
				(font
					(size 1.27 1.27)
				)
			)
		)
		(duplicate_pad_numbers_are_jumpers no)
		(fp_line
			(start -0.7874 0.4064)
			(end -0.7874 -0.4064)
			(stroke
				(width 0.1524)
				(type default)
			)
			(layer "F.SilkS")
		)
		(fp_line
			(start 0.7874 0.4064)
			(end -0.7874 0.4064)
			(stroke
				(width 0.1524)
				(type default)
			)
			(layer "F.SilkS")
		)
		(fp_line
			(start -0.7874 -0.4064)
			(end 0.7874 -0.4064)
			(stroke
				(width 0.1524)
				(type default)
			)
			(layer "F.SilkS")
		)
		(fp_line
			(start 0.7874 -0.4064)
			(end 0.7874 0.4064)
			(stroke
				(width 0.1524)
				(type default)
			)
			(layer "F.SilkS")
		)
		(fp_line
			(start -0.67945 0.3048)
			(end -0.67945 -0.305054)
			(stroke
				(width 0.1)
				(type default)
			)
			(layer "F.Fab")
		)
		(fp_line
			(start -0.12065 0.3048)
			(end -0.67945 0.3048)
			(stroke
				(width 0.1)
				(type default)
			)
			(layer "F.Fab")
		)
		(fp_line
			(start 0.120396 0.3048)
			(end 0.120396 0.2794)
			(stroke
				(width 0.1)
				(type default)
			)
			(layer "F.Fab")
		)
		(fp_line
			(start 0.67945 0.3048)
			(end 0.120396 0.3048)
			(stroke
				(width 0.1)
				(type default)
			)
			(layer "F.Fab")
		)
		(fp_line
			(start -0.12065 0.2794)
			(end -0.12065 0.3048)
			(stroke
				(width 0.1)
				(type default)
			)
			(layer "F.Fab")
		)
		(fp_line
			(start 0.120396 0.2794)
			(end -0.12065 0.2794)
			(stroke
				(width 0.1)
				(type default)
			)
			(layer "F.Fab")
		)
		(fp_line
			(start -0.12065 -0.2794)
			(end 0.12065 -0.2794)
			(stroke
				(width 0.1)
				(type default)
			)
			(layer "F.Fab")
		)
		(fp_line
			(start 0.12065 -0.2794)
			(end 0.12065 -0.3048)
			(stroke
				(width 0.1)
				(type default)
			)
			(layer "F.Fab")
		)
		(fp_line
			(start 0.12065 -0.3048)
			(end 0.67945 -0.3048)
			(stroke
				(width 0.1)
				(type default)
			)
			(layer "F.Fab")
		)
		(fp_line
			(start 0.67945 -0.3048)
			(end 0.67945 0.3048)
			(stroke
				(width 0.1)
				(type default)
			)
			(layer "F.Fab")
		)
		(fp_line
			(start -0.67945 -0.305054)
			(end -0.12065 -0.305054)
			(stroke
				(width 0.1)
				(type default)
			)
			(layer "F.Fab")
		)
		(fp_line
			(start -0.12065 -0.305054)
			(end -0.12065 -0.2794)
			(stroke
				(width 0.1)
				(type default)
			)
			(layer "F.Fab")
		)
		(pad "1" smd circle
			(at -0.40005 0 270)
			(size 0 0)
			(layers "F.Cu" "F.Mask" "F.Paste")
			(net "CLK_50M_RMII")
		)
		(pad "2" smd circle
			(at 0.40005 0 270)
			(size 0 0)
			(layers "F.Cu" "F.Mask" "F.Paste")
			(net "CLK_50M_RMII_R")
		)
	)
	(footprint ""
		(layer "F.Cu")
		(at 129.411984 -66.938906 90)
		(property "Reference" "R928"
			(at 0 0 90)
			(layer "F.SilkS")
			(hide yes)
			(effects
				(font
					(size 1.27 1.27)
				)
			)
		)
		(property "Value" ""
			(at 0 0 90)
			(layer "F.Fab")
			(effects
				(font
					(size 1.27 1.27)
				)
			)
		)
		(duplicate_pad_numbers_are_jumpers no)
		(fp_line
			(start 0.7874 -0.4064)
			(end 0.7874 0.4064)
			(stroke
				(width 0.1524)
				(type default)
			)
			(layer "F.SilkS")
		)
		(fp_line
			(start -0.7874 -0.4064)
			(end 0.7874 -0.4064)
			(stroke
				(width 0.1524)
				(type default)
			)
			(layer "F.SilkS")
		)
		(fp_line
			(start 0.7874 0.4064)
			(end -0.7874 0.4064)
			(stroke
				(width 0.1524)
				(type default)
			)
			(layer "F.SilkS")
		)
		(fp_line
			(start -0.7874 0.4064)
			(end -0.7874 -0.4064)
			(stroke
				(width 0.1524)
				(type default)
			)
			(layer "F.SilkS")
		)
		(fp_line
			(start -0.12065 -0.305054)
			(end -0.12065 -0.2794)
			(stroke
				(width 0.1)
				(type default)
			)
			(layer "F.Fab")
		)
		(fp_line
			(start -0.67945 -0.305054)
			(end -0.12065 -0.305054)
			(stroke
				(width 0.1)
				(type default)
			)
			(layer "F.Fab")
		)
		(fp_line
			(start 0.67945 -0.3048)
			(end 0.67945 0.3048)
			(stroke
				(width 0.1)
				(type default)
			)
			(layer "F.Fab")
		)
		(fp_line
			(start 0.12065 -0.3048)
			(end 0.67945 -0.3048)
			(stroke
				(width 0.1)
				(type default)
			)
			(layer "F.Fab")
		)
		(fp_line
			(start 0.12065 -0.2794)
			(end 0.12065 -0.3048)
			(stroke
				(width 0.1)
				(type default)
			)
			(layer "F.Fab")
		)
		(fp_line
			(start -0.12065 -0.2794)
			(end 0.12065 -0.2794)
			(stroke
				(width 0.1)
				(type default)
			)
			(layer "F.Fab")
		)
		(fp_line
			(start 0.120396 0.2794)
			(end -0.12065 0.2794)
			(stroke
				(width 0.1)
				(type default)
			)
			(layer "F.Fab")
		)
		(fp_line
			(start -0.12065 0.2794)
			(end -0.12065 0.3048)
			(stroke
				(width 0.1)
				(type default)
			)
			(layer "F.Fab")
		)
		(fp_line
			(start 0.67945 0.3048)
			(end 0.120396 0.3048)
			(stroke
				(width 0.1)
				(type default)
			)
			(layer "F.Fab")
		)
		(fp_line
			(start 0.120396 0.3048)
			(end 0.120396 0.2794)
			(stroke
				(width 0.1)
				(type default)
			)
			(layer "F.Fab")
		)
		(fp_line
			(start -0.12065 0.3048)
			(end -0.67945 0.3048)
			(stroke
				(width 0.1)
				(type default)
			)
			(layer "F.Fab")
		)
		(fp_line
			(start -0.67945 0.3048)
			(end -0.67945 -0.305054)
			(stroke
				(width 0.1)
				(type default)
			)
			(layer "F.Fab")
		)
		(pad "1" smd circle
			(at -0.40005 0 90)
			(size 0 0)
			(layers "F.Cu" "F.Mask" "F.Paste")
			(net "P3V3_AUX")
		)
		(pad "2" smd circle
			(at 0.40005 0 90)
			(size 0 0)
			(layers "F.Cu" "F.Mask" "F.Paste")
			(net "JTAG_BMC_PLD_TDO")
		)
	)
	(footprint ""
		(layer "F.Cu")
		(at 448.672458 -93.509592 180)
		(property "Reference" "R3617"
			(at 0 0 180)
			(layer "F.SilkS")
			(hide yes)
			(effects
				(font
					(size 1.27 1.27)
				)
			)
		)
		(property "Value" ""
			(at 0 0 180)
			(layer "F.Fab")
			(effects
				(font
					(size 1.27 1.27)
				)
			)
		)
		(duplicate_pad_numbers_are_jumpers no)
		(fp_line
			(start 0.7874 0.4064)
			(end -0.7874 0.4064)
			(stroke
				(width 0.1524)
				(type default)
			)
			(layer "F.SilkS")
		)
		(fp_line
			(start 0.7874 -0.4064)
			(end 0.7874 0.4064)
			(stroke
				(width 0.1524)
				(type default)
			)
			(layer "F.SilkS")
		)
		(fp_line
			(start -0.7874 0.4064)
			(end -0.7874 -0.4064)
			(stroke
				(width 0.1524)
				(type default)
			)
			(layer "F.SilkS")
		)
		(fp_line
			(start -0.7874 -0.4064)
			(end 0.7874 -0.4064)
			(stroke
				(width 0.1524)
				(type default)
			)
			(layer "F.SilkS")
		)
		(fp_line
			(start 0.67945 0.3048)
			(end 0.120396 0.3048)
			(stroke
				(width 0.1)
				(type default)
			)
			(layer "F.Fab")
		)
		(fp_line
			(start 0.67945 -0.3048)
			(end 0.67945 0.3048)
			(stroke
				(width 0.1)
				(type default)
			)
			(layer "F.Fab")
		)
		(fp_line
			(start 0.12065 -0.2794)
			(end 0.12065 -0.3048)
			(stroke
				(width 0.1)
				(type default)
			)
			(layer "F.Fab")
		)
		(fp_line
			(start 0.12065 -0.3048)
			(end 0.67945 -0.3048)
			(stroke
				(width 0.1)
				(type default)
			)
			(layer "F.Fab")
		)
		(fp_line
			(start 0.120396 0.3048)
			(end 0.120396 0.2794)
			(stroke
				(width 0.1)
				(type default)
			)
			(layer "F.Fab")
		)
		(fp_line
			(start 0.120396 0.2794)
			(end -0.12065 0.2794)
			(stroke
				(width 0.1)
				(type default)
			)
			(layer "F.Fab")
		)
		(fp_line
			(start -0.12065 0.3048)
			(end -0.67945 0.3048)
			(stroke
				(width 0.1)
				(type default)
			)
			(layer "F.Fab")
		)
		(fp_line
			(start -0.12065 0.2794)
			(end -0.12065 0.3048)
			(stroke
				(width 0.1)
				(type default)
			)
			(layer "F.Fab")
		)
		(fp_line
			(start -0.12065 -0.2794)
			(end 0.12065 -0.2794)
			(stroke
				(width 0.1)
				(type default)
			)
			(layer "F.Fab")
		)
		(fp_line
			(start -0.12065 -0.305054)
			(end -0.12065 -0.2794)
			(stroke
				(width 0.1)
				(type default)
			)
			(layer "F.Fab")
		)
		(fp_line
			(start -0.67945 0.3048)
			(end -0.67945 -0.305054)
			(stroke
				(width 0.1)
				(type default)
			)
			(layer "F.Fab")
		)
		(fp_line
			(start -0.67945 -0.305054)
			(end -0.12065 -0.305054)
			(stroke
				(width 0.1)
				(type default)
			)
			(layer "F.Fab")
		)
		(pad "1" smd circle
			(at -0.40005 0 180)
			(size 0 0)
			(layers "F.Cu" "F.Mask" "F.Paste")
			(net "GND")
		)
		(pad "2" smd circle
			(at 0.40005 0 180)
			(size 0 0)
			(layers "F.Cu" "F.Mask" "F.Paste")
			(net "INA230_1_A0")
		)
	)
	(footprint ""
		(layer "F.Cu")
		(at 145.65884 -92.634308 -90)
		(property "Reference" "R4052"
			(at 0 0 270)
			(layer "F.SilkS")
			(hide yes)
			(effects
				(font
					(size 1.27 1.27)
				)
			)
		)
		(property "Value" ""
			(at 0 0 270)
			(layer "F.Fab")
			(effects
				(font
					(size 1.27 1.27)
				)
			)
		)
		(duplicate_pad_numbers_are_jumpers no)
		(fp_line
			(start -0.7874 0.4064)
			(end -0.7874 -0.4064)
			(stroke
				(width 0.1524)
				(type default)
			)
			(layer "F.SilkS")
		)
		(fp_line
			(start 0.7874 0.4064)
			(end -0.7874 0.4064)
			(stroke
				(width 0.1524)
				(type default)
			)
			(layer "F.SilkS")
		)
		(fp_line
			(start -0.7874 -0.4064)
			(end 0.7874 -0.4064)
			(stroke
				(width 0.1524)
				(type default)
			)
			(layer "F.SilkS")
		)
		(fp_line
			(start 0.7874 -0.4064)
			(end 0.7874 0.4064)
			(stroke
				(width 0.1524)
				(type default)
			)
			(layer "F.SilkS")
		)
		(fp_line
			(start -0.67945 0.3048)
			(end -0.67945 -0.305054)
			(stroke
				(width 0.1)
				(type default)
			)
			(layer "F.Fab")
		)
		(fp_line
			(start -0.12065 0.3048)
			(end -0.67945 0.3048)
			(stroke
				(width 0.1)
				(type default)
			)
			(layer "F.Fab")
		)
		(fp_line
			(start 0.120396 0.3048)
			(end 0.120396 0.2794)
			(stroke
				(width 0.1)
				(type default)
			)
			(layer "F.Fab")
		)
		(fp_line
			(start 0.67945 0.3048)
			(end 0.120396 0.3048)
			(stroke
				(width 0.1)
				(type default)
			)
			(layer "F.Fab")
		)
		(fp_line
			(start -0.12065 0.2794)
			(end -0.12065 0.3048)
			(stroke
				(width 0.1)
				(type default)
			)
			(layer "F.Fab")
		)
		(fp_line
			(start 0.120396 0.2794)
			(end -0.12065 0.2794)
			(stroke
				(width 0.1)
				(type default)
			)
			(layer "F.Fab")
		)
		(fp_line
			(start -0.12065 -0.2794)
			(end 0.12065 -0.2794)
			(stroke
				(width 0.1)
				(type default)
			)
			(layer "F.Fab")
		)
		(fp_line
			(start 0.12065 -0.2794)
			(end 0.12065 -0.3048)
			(stroke
				(width 0.1)
				(type default)
			)
			(layer "F.Fab")
		)
		(fp_line
			(start 0.12065 -0.3048)
			(end 0.67945 -0.3048)
			(stroke
				(width 0.1)
				(type default)
			)
			(layer "F.Fab")
		)
		(fp_line
			(start 0.67945 -0.3048)
			(end 0.67945 0.3048)
			(stroke
				(width 0.1)
				(type default)
			)
			(layer "F.Fab")
		)
		(fp_line
			(start -0.67945 -0.305054)
			(end -0.12065 -0.305054)
			(stroke
				(width 0.1)
				(type default)
			)
			(layer "F.Fab")
		)
		(fp_line
			(start -0.12065 -0.305054)
			(end -0.12065 -0.2794)
			(stroke
				(width 0.1)
				(type default)
			)
			(layer "F.Fab")
		)
		(pad "1" smd circle
			(at -0.40005 0 270)
			(size 0 0)
			(layers "F.Cu" "F.Mask" "F.Paste")
			(net "H_CPU_ERR2_LVC2_R_N")
		)
		(pad "2" smd circle
			(at 0.40005 0 270)
			(size 0 0)
			(layers "F.Cu" "F.Mask" "F.Paste")
			(net "H_CPU_ERR2_LVC2_N")
		)
	)
)
